(kicad_pcb
	(version 20241229)
	(generator "pcbnew")
	(generator_version "9.0")
	(general
		(thickness 1.599998)
		(legacy_teardrops no)
	)
	(paper "A4")
	(title_block
		(date "2023-02-12")
		(rev "1.1.5")
		(comment 9 "footprints 397-401 of 473")
	)
	(layers
		(0 "F.Cu" signal)
		(4 "In1.Cu" power "In1.GND")
		(6 "In2.Cu" signal)
		(8 "In3.Cu" power "In3.GND")
		(10 "In4.Cu" power "In4.VCC")
		(12 "In5.Cu" signal)
		(14 "In6.Cu" power "In6.VCC")
		(2 "B.Cu" signal)
		(9 "F.Adhes" user "F.Adhesive")
		(11 "B.Adhes" user "B.Adhesive")
		(13 "F.Paste" user)
		(15 "B.Paste" user)
		(5 "F.SilkS" user "F.Silkscreen")
		(7 "B.SilkS" user "B.Silkscreen")
		(1 "F.Mask" user)
		(3 "B.Mask" user)
		(17 "Dwgs.User" user "User.Drawings")
		(19 "Cmts.User" user "User.Comments")
		(21 "Eco1.User" user "User.Eco1")
		(23 "Eco2.User" user "User.Eco2")
		(25 "Edge.Cuts" user)
		(27 "Margin" user)
		(31 "F.CrtYd" user "F.Courtyard")
		(29 "B.CrtYd" user "B.Courtyard")
		(35 "F.Fab" user)
		(33 "B.Fab" user)
	)
	(footprint "antmicro-footprints:MicroSD_Amphenol_1140084168"
		(layer "B.Cu")
		(at 174.770666 127.719218 180)
		(property "Reference" "J3"
			(at -6.6 6.5 0)
			(layer "B.SilkS")
			(effects
				(font
					(size 0.7 0.7)
					(thickness 0.15)
				)
				(justify left bottom mirror)
			)
		)
		(property "Value" "MicroSD_1140084168"
			(at -6.9 -11.4 0)
			(layer "B.Fab")
			(effects
				(font
					(size 0.7 0.7)
					(thickness 0.15)
				)
				(justify left bottom mirror)
			)
		)
		(property "Description" "Micro SD Right Angle, PCB Mount"
			(at 0 0 180)
			(layer "F.Fab")
			(hide yes)
			(effects
				(font
					(size 1.27 1.27)
					(thickness 0.15)
				)
			)
		)
		(property "Author" "Antmicro"
			(at 349.541332 255.438436 0)
			(layer "B.Fab")
			(hide yes)
			(effects
				(font
					(size 1 1)
					(thickness 0.15)
				)
				(justify mirror)
			)
		)
		(property "License" "Apache-2.0"
			(at 349.541332 255.438436 0)
			(layer "B.Fab")
			(hide yes)
			(effects
				(font
					(size 1 1)
					(thickness 0.15)
				)
				(justify mirror)
			)
		)
		(property "MPN" "1140084168"
			(at 349.541332 255.438436 0)
			(layer "B.Fab")
			(hide yes)
			(effects
				(font
					(size 1 1)
					(thickness 0.15)
				)
				(justify mirror)
			)
		)
		(property "Manufacturer" "Amphenol"
			(at 349.541332 255.438436 0)
			(layer "B.Fab")
			(hide yes)
			(effects
				(font
					(size 1 1)
					(thickness 0.15)
				)
				(justify mirror)
			)
		)
		(sheetname "Interfaces")
		(sheetfile "interfaces.kicad_sch")
		(attr smd)
		(fp_line
			(start 6.2 6.1)
			(end 6.1 6.1)
			(stroke
				(width 0.15)
				(type solid)
			)
			(layer "B.SilkS")
		)
		(fp_line
			(start 6.2 4)
			(end 6.2 6.1)
			(stroke
				(width 0.15)
				(type solid)
			)
			(layer "B.SilkS")
		)
		(fp_line
			(start 6.2 -4.2)
			(end 6.2 2.2)
			(stroke
				(width 0.15)
				(type solid)
			)
			(layer "B.SilkS")
		)
		(fp_line
			(start 4.8 6.1)
			(end -6.3 6.1)
			(stroke
				(width 0.15)
				(type solid)
			)
			(layer "B.SilkS")
		)
		(fp_line
			(start -6.3 6.1)
			(end -6.3 4.7)
			(stroke
				(width 0.15)
				(type solid)
			)
			(layer "B.SilkS")
		)
		(fp_line
			(start -6.3 1.6)
			(end -6.3 -4.2)
			(stroke
				(width 0.15)
				(type solid)
			)
			(layer "B.SilkS")
		)
		(fp_rect
			(start -6.5 6.3)
			(end 6.4 -6.2)
			(stroke
				(width 0.05)
				(type solid)
			)
			(fill no)
			(layer "B.CrtYd")
		)
		(fp_line
			(start 5.4 -8.9)
			(end 4.6 -8.7)
			(stroke
				(width 0.12)
				(type solid)
			)
			(layer "B.Fab")
		)
		(fp_line
			(start 5.4 -9.2)
			(end 4.6 -9)
			(stroke
				(width 0.12)
				(type solid)
			)
			(layer "B.Fab")
		)
		(fp_line
			(start 5.4 -9.5)
			(end 5.4 -5.8)
			(stroke
				(width 0.12)
				(type solid)
			)
			(layer "B.Fab")
		)
		(fp_line
			(start 4.9 -10)
			(end -5.1 -10)
			(stroke
				(width 0.12)
				(type solid)
			)
			(layer "B.Fab")
		)
		(fp_line
			(start 4.6 -8.7)
			(end 2.9 -8.4)
			(stroke
				(width 0.12)
				(type solid)
			)
			(layer "B.Fab")
		)
		(fp_line
			(start 4.6 -9)
			(end 2.9 -8.7)
			(stroke
				(width 0.12)
				(type solid)
			)
			(layer "B.Fab")
		)
		(fp_line
			(start 2.9 -8.4)
			(end 2.1 -8.3)
			(stroke
				(width 0.12)
				(type solid)
			)
			(layer "B.Fab")
		)
		(fp_line
			(start 2.9 -8.7)
			(end 2.1 -8.6)
			(stroke
				(width 0.12)
				(type solid)
			)
			(layer "B.Fab")
		)
		(fp_line
			(start 2.1 -8.3)
			(end 0.8 -8.2)
			(stroke
				(width 0.12)
				(type solid)
			)
			(layer "B.Fab")
		)
		(fp_line
			(start 2.1 -8.6)
			(end 0.8 -8.5)
			(stroke
				(width 0.12)
				(type solid)
			)
			(layer "B.Fab")
		)
		(fp_line
			(start 0.8 -8.2)
			(end -1 -8.2)
			(stroke
				(width 0.12)
				(type solid)
			)
			(layer "B.Fab")
		)
		(fp_line
			(start 0.8 -8.5)
			(end -1 -8.5)
			(stroke
				(width 0.12)
				(type solid)
			)
			(layer "B.Fab")
		)
		(fp_line
			(start -1 -8.2)
			(end -2.3 -8.3)
			(stroke
				(width 0.12)
				(type solid)
			)
			(layer "B.Fab")
		)
		(fp_line
			(start -1 -8.5)
			(end -2.3 -8.6)
			(stroke
				(width 0.12)
				(type solid)
			)
			(layer "B.Fab")
		)
		(fp_line
			(start -2.3 -8.3)
			(end -3.8 -8.5)
			(stroke
				(width 0.12)
				(type solid)
			)
			(layer "B.Fab")
		)
		(fp_line
			(start -2.3 -8.6)
			(end -3.8 -8.8)
			(stroke
				(width 0.12)
				(type solid)
			)
			(layer "B.Fab")
		)
		(fp_line
			(start -3.8 -8.5)
			(end -5.1 -8.8)
			(stroke
				(width 0.12)
				(type solid)
			)
			(layer "B.Fab")
		)
		(fp_line
			(start -3.8 -8.8)
			(end -5.1 -9.1)
			(stroke
				(width 0.12)
				(type solid)
			)
			(layer "B.Fab")
		)
		(fp_line
			(start -5.1 -8.8)
			(end -5.6 -8.9)
			(stroke
				(width 0.12)
				(type solid)
			)
			(layer "B.Fab")
		)
		(fp_line
			(start -5.1 -9.1)
			(end -5.6 -9.2)
			(stroke
				(width 0.12)
				(type solid)
			)
			(layer "B.Fab")
		)
		(fp_line
			(start -5.6 -5.8)
			(end -5.6 -9.5)
			(stroke
				(width 0.12)
				(type solid)
			)
			(layer "B.Fab")
		)
		(fp_rect
			(start -6 5.8)
			(end 5.999 -5.799)
			(stroke
				(width 0.1)
				(type solid)
			)
			(fill no)
			(layer "B.Fab")
		)
		(fp_arc
			(start 4.9 -10)
			(mid 5.253553 -9.853553)
			(end 5.4 -9.5)
			(stroke
				(width 0.12)
				(type solid)
			)
			(layer "B.Fab")
		)
		(fp_arc
			(start -5.6 -9.5)
			(mid -5.453553 -9.853553)
			(end -5.1 -10)
			(stroke
				(width 0.12)
				(type solid)
			)
			(layer "B.Fab")
		)
		(pad "1" smd rect
			(at 3.124 -5.254)
			(size 0.7 1.75)
			(layers "B.Cu" "B.Mask" "B.Paste")
			(net 197 "SD_DAT2")
			(pinfunction "DAT2")
			(pintype "bidirectional")
		)
		(pad "2" smd rect
			(at 2.024 -5.254)
			(size 0.7 1.75)
			(layers "B.Cu" "B.Mask" "B.Paste")
			(net 196 "SD_DAT3")
			(pinfunction "CD/DAT3")
			(pintype "bidirectional")
		)
		(pad "3" smd rect
			(at 0.925 -5.254)
			(size 0.7 1.75)
			(layers "B.Cu" "B.Mask" "B.Paste")
			(net 195 "SD_CMD")
			(pinfunction "CMD")
			(pintype "bidirectional")
		)
		(pad "4" smd rect
			(at -0.176 -5.254)
			(size 0.7 1.75)
			(layers "B.Cu" "B.Mask" "B.Paste")
			(net 459 "3V3_SYS")
			(pinfunction "VDD")
			(pintype "power_in")
		)
		(pad "5" smd rect
			(at -1.276 -5.254)
			(size 0.7 1.75)
			(layers "B.Cu" "B.Mask" "B.Paste")
			(net 194 "SD_CLK")
			(pinfunction "CLK")
			(pintype "output")
		)
		(pad "6" smd rect
			(at -2.375 -5.254)
			(size 0.7 1.75)
			(layers "B.Cu" "B.Mask" "B.Paste")
			(net 5 "GND")
			(pinfunction "VSS")
			(pintype "power_in")
		)
		(pad "7" smd rect
			(at -3.476 -5.254)
			(size 0.7 1.75)
			(layers "B.Cu" "B.Mask" "B.Paste")
			(net 193 "SD_DAT0")
			(pinfunction "DAT0")
			(pintype "bidirectional")
		)
		(pad "8" smd rect
			(at -4.576 -5.254)
			(size 0.7 1.75)
			(layers "B.Cu" "B.Mask" "B.Paste")
			(net 192 "SD_DAT1")
			(pinfunction "DAT1")
			(pintype "bidirectional")
		)
		(pad "9" smd rect
			(at -5.675 4.05 180)
			(size 1.4 1)
			(layers "B.Cu" "B.Mask" "B.Paste")
			(net 85 "Net-(J3-CD1)")
			(pinfunction "CD1")
			(pintype "passive")
		)
		(pad "10" smd rect
			(at 5.424 5.531 90)
			(size 1.4 1)
			(layers "B.Cu" "B.Mask" "B.Paste")
			(net 5 "GND")
			(pinfunction "CD2")
			(pintype "passive")
		)
		(pad "SH" smd rect
			(at -5.976 2.48 90)
			(size 1.5 0.8)
			(layers "B.Cu" "B.Mask" "B.Paste")
			(net 5 "GND")
			(pinfunction "Shell")
			(pintype "passive")
		)
		(pad "SH" smd rect
			(at -5.776 -5.129 180)
			(size 1.3 1.5)
			(layers "B.Cu" "B.Mask" "B.Paste")
			(net 5 "GND")
			(pinfunction "Shell")
			(pintype "passive")
		)
		(pad "SH" smd rect
			(at 5.575 -5.129 180)
			(size 1.5 1.5)
			(layers "B.Cu" "B.Mask" "B.Paste")
			(net 5 "GND")
			(pinfunction "Shell")
			(pintype "passive")
		)
		(pad "SH" smd rect
			(at 5.874 3.13 90)
			(size 1.5 0.8)
			(layers "B.Cu" "B.Mask" "B.Paste")
			(net 5 "GND")
			(pinfunction "Shell")
			(pintype "passive")
		)
	)
	(footprint "antmicro-footprints:C_0402_1005Metric"
		(layer "B.Cu")
		(at 153.4922 94.742 180)
		(descr "Capacitor SMD 0402")
		(tags "capacitor SMD 0402")
		(property "Reference" "C2"
			(at -0.8078 0.542 0)
			(layer "B.SilkS")
			(effects
				(font
					(size 0.7 0.7)
					(thickness 0.15)
				)
				(justify left bottom mirror)
			)
		)
		(property "Value" "C_100n_6V3_0402"
			(at 0 -1.4 0)
			(layer "B.Fab")
			(effects
				(font
					(size 0.7 0.7)
					(thickness 0.15)
				)
				(justify left bottom mirror)
			)
		)
		(property "Description" " "
			(at 0 0 180)
			(layer "F.Fab")
			(hide yes)
			(effects
				(font
					(size 1.27 1.27)
					(thickness 0.15)
				)
			)
		)
		(property "Author" "Antmicro"
			(at 306.9844 189.484 0)
			(layer "B.Fab")
			(hide yes)
			(effects
				(font
					(size 1 1)
					(thickness 0.15)
				)
				(justify mirror)
			)
		)
		(property "Dielectric" ""
			(at 306.9844 189.484 0)
			(layer "B.Fab")
			(hide yes)
			(effects
				(font
					(size 1 1)
					(thickness 0.15)
				)
				(justify mirror)
			)
		)
		(property "License" "Apache-2.0"
			(at 306.9844 189.484 0)
			(layer "B.Fab")
			(hide yes)
			(effects
				(font
					(size 1 1)
					(thickness 0.15)
				)
				(justify mirror)
			)
		)
		(property "MPN" "0402X104K6R3CT"
			(at 306.9844 189.484 0)
			(layer "B.Fab")
			(hide yes)
			(effects
				(font
					(size 1 1)
					(thickness 0.15)
				)
				(justify mirror)
			)
		)
		(property "Manufacturer" "Walsin"
			(at 306.9844 189.484 0)
			(layer "B.Fab")
			(hide yes)
			(effects
				(font
					(size 1 1)
					(thickness 0.15)
				)
				(justify mirror)
			)
		)
		(property "Val" "100n"
			(at 306.9844 189.484 0)
			(layer "B.Fab")
			(hide yes)
			(effects
				(font
					(size 1 1)
					(thickness 0.15)
				)
				(justify mirror)
			)
		)
		(property "Voltage" ""
			(at 306.9844 189.484 0)
			(layer "B.Fab")
			(hide yes)
			(effects
				(font
					(size 1 1)
					(thickness 0.15)
				)
				(justify mirror)
			)
		)
		(sheetname "HyperRAM")
		(sheetfile "hyperram.kicad_sch")
		(attr smd)
		(fp_rect
			(start -0.94 0.47)
			(end 0.94 -0.47)
			(stroke
				(width 0.05)
				(type solid)
			)
			(fill no)
			(layer "B.CrtYd")
		)
		(fp_rect
			(start -0.499 0.249)
			(end 0.499 -0.249)
			(stroke
				(width 0.15)
				(type solid)
			)
			(fill no)
			(layer "B.Fab")
		)
		(pad "1" smd roundrect
			(at -0.484 0 180)
			(size 0.59 0.64)
			(layers "B.Cu" "B.Mask" "B.Paste")
			(roundrect_rratio 0.25)
			(net 459 "3V3_SYS")
			(pintype "passive")
		)
		(pad "2" smd roundrect
			(at 0.484 0 180)
			(size 0.59 0.64)
			(layers "B.Cu" "B.Mask" "B.Paste")
			(roundrect_rratio 0.25)
			(net 5 "GND")
			(pintype "passive")
		)
	)
	(footprint "antmicro-footprints:C_0402_1005Metric"
		(layer "B.Cu")
		(at 150.2156 99.2632 90)
		(descr "Capacitor SMD 0402")
		(tags "capacitor SMD 0402")
		(property "Reference" "C3"
			(at 0.7632 -0.5156 270)
			(layer "B.SilkS")
			(effects
				(font
					(size 0.7 0.7)
					(thickness 0.15)
				)
				(justify left bottom mirror)
			)
		)
		(property "Value" "C_100n_6V3_0402"
			(at 0 -1.4 270)
			(layer "B.Fab")
			(effects
				(font
					(size 0.7 0.7)
					(thickness 0.15)
				)
				(justify left bottom mirror)
			)
		)
		(property "Description" " "
			(at 0 0 90)
			(layer "F.Fab")
			(hide yes)
			(effects
				(font
					(size 1.27 1.27)
					(thickness 0.15)
				)
			)
		)
		(property "Author" "Antmicro"
			(at 249.4788 -50.9524 0)
			(layer "B.Fab")
			(hide yes)
			(effects
				(font
					(size 1 1)
					(thickness 0.15)
				)
				(justify mirror)
			)
		)
		(property "Dielectric" ""
			(at 249.4788 -50.9524 0)
			(layer "B.Fab")
			(hide yes)
			(effects
				(font
					(size 1 1)
					(thickness 0.15)
				)
				(justify mirror)
			)
		)
		(property "License" "Apache-2.0"
			(at 249.4788 -50.9524 0)
			(layer "B.Fab")
			(hide yes)
			(effects
				(font
					(size 1 1)
					(thickness 0.15)
				)
				(justify mirror)
			)
		)
		(property "MPN" "0402X104K6R3CT"
			(at 249.4788 -50.9524 0)
			(layer "B.Fab")
			(hide yes)
			(effects
				(font
					(size 1 1)
					(thickness 0.15)
				)
				(justify mirror)
			)
		)
		(property "Manufacturer" "Walsin"
			(at 249.4788 -50.9524 0)
			(layer "B.Fab")
			(hide yes)
			(effects
				(font
					(size 1 1)
					(thickness 0.15)
				)
				(justify mirror)
			)
		)
		(property "Val" "100n"
			(at 249.4788 -50.9524 0)
			(layer "B.Fab")
			(hide yes)
			(effects
				(font
					(size 1 1)
					(thickness 0.15)
				)
				(justify mirror)
			)
		)
		(property "Voltage" ""
			(at 249.4788 -50.9524 0)
			(layer "B.Fab")
			(hide yes)
			(effects
				(font
					(size 1 1)
					(thickness 0.15)
				)
				(justify mirror)
			)
		)
		(sheetname "HyperRAM")
		(sheetfile "hyperram.kicad_sch")
		(attr smd)
		(fp_rect
			(start -0.94 0.47)
			(end 0.94 -0.47)
			(stroke
				(width 0.05)
				(type solid)
			)
			(fill no)
			(layer "B.CrtYd")
		)
		(fp_rect
			(start -0.499 0.249)
			(end 0.499 -0.249)
			(stroke
				(width 0.15)
				(type solid)
			)
			(fill no)
			(layer "B.Fab")
		)
		(pad "1" smd roundrect
			(at -0.484 0 90)
			(size 0.59 0.64)
			(layers "B.Cu" "B.Mask" "B.Paste")
			(roundrect_rratio 0.25)
			(net 459 "3V3_SYS")
			(pintype "passive")
		)
		(pad "2" smd roundrect
			(at 0.484 0 90)
			(size 0.59 0.64)
			(layers "B.Cu" "B.Mask" "B.Paste")
			(roundrect_rratio 0.25)
			(net 5 "GND")
			(pintype "passive")
		)
	)
	(footprint "antmicro-footprints:C_0402_1005Metric"
		(layer "B.Cu")
		(at 150.9014 96.7232 -90)
		(descr "Capacitor SMD 0402")
		(tags "capacitor SMD 0402")
		(property "Reference" "C4"
			(at -0.7232 0.5014 90)
			(layer "B.SilkS")
			(effects
				(font
					(size 0.7 0.7)
					(thickness 0.15)
				)
				(justify left bottom mirror)
			)
		)
		(property "Value" "C_100n_6V3_0402"
			(at 0 -1.4 90)
			(layer "B.Fab")
			(effects
				(font
					(size 0.7 0.7)
					(thickness 0.15)
				)
				(justify left bottom mirror)
			)
		)
		(property "Description" " "
			(at 0 0 270)
			(layer "F.Fab")
			(hide yes)
			(effects
				(font
					(size 1.27 1.27)
					(thickness 0.15)
				)
			)
		)
		(property "Author" "Antmicro"
			(at 54.1782 247.6246 0)
			(layer "B.Fab")
			(hide yes)
			(effects
				(font
					(size 1 1)
					(thickness 0.15)
				)
				(justify mirror)
			)
		)
		(property "Dielectric" ""
			(at 54.1782 247.6246 0)
			(layer "B.Fab")
			(hide yes)
			(effects
				(font
					(size 1 1)
					(thickness 0.15)
				)
				(justify mirror)
			)
		)
		(property "License" "Apache-2.0"
			(at 54.1782 247.6246 0)
			(layer "B.Fab")
			(hide yes)
			(effects
				(font
					(size 1 1)
					(thickness 0.15)
				)
				(justify mirror)
			)
		)
		(property "MPN" "0402X104K6R3CT"
			(at 54.1782 247.6246 0)
			(layer "B.Fab")
			(hide yes)
			(effects
				(font
					(size 1 1)
					(thickness 0.15)
				)
				(justify mirror)
			)
		)
		(property "Manufacturer" "Walsin"
			(at 54.1782 247.6246 0)
			(layer "B.Fab")
			(hide yes)
			(effects
				(font
					(size 1 1)
					(thickness 0.15)
				)
				(justify mirror)
			)
		)
		(property "Val" "100n"
			(at 54.1782 247.6246 0)
			(layer "B.Fab")
			(hide yes)
			(effects
				(font
					(size 1 1)
					(thickness 0.15)
				)
				(justify mirror)
			)
		)
		(property "Voltage" ""
			(at 54.1782 247.6246 0)
			(layer "B.Fab")
			(hide yes)
			(effects
				(font
					(size 1 1)
					(thickness 0.15)
				)
				(justify mirror)
			)
		)
		(sheetname "HyperRAM")
		(sheetfile "hyperram.kicad_sch")
		(attr smd)
		(fp_rect
			(start -0.94 0.47)
			(end 0.94 -0.47)
			(stroke
				(width 0.05)
				(type solid)
			)
			(fill no)
			(layer "B.CrtYd")
		)
		(fp_rect
			(start -0.499 0.249)
			(end 0.499 -0.249)
			(stroke
				(width 0.15)
				(type solid)
			)
			(fill no)
			(layer "B.Fab")
		)
		(pad "1" smd roundrect
			(at -0.484 0 270)
			(size 0.59 0.64)
			(layers "B.Cu" "B.Mask" "B.Paste")
			(roundrect_rratio 0.25)
			(net 459 "3V3_SYS")
			(pintype "passive")
		)
		(pad "2" smd roundrect
			(at 0.484 0 270)
			(size 0.59 0.64)
			(layers "B.Cu" "B.Mask" "B.Paste")
			(roundrect_rratio 0.25)
			(net 5 "GND")
			(pintype "passive")
		)
	)
	(footprint "antmicro-footprints:C_0603_1608Metric"
		(layer "B.Cu")
		(at 173 81.8)
		(descr "Capacitor SMD 0603")
		(tags "capacitor 0603")
		(property "Reference" "C134"
			(at 1.4 1.4 180)
			(layer "B.SilkS")
			(effects
				(font
					(size 0.7 0.7)
					(thickness 0.15)
				)
				(justify left bottom mirror)
			)
		)
		(property "Value" "C_10n_0603"
			(at 0 -1.6 180)
			(layer "B.Fab")
			(effects
				(font
					(size 0.7 0.7)
					(thickness 0.15)
				)
				(justify left bottom mirror)
			)
		)
		(property "Description" " "
			(at 0 0 0)
			(layer "F.Fab")
			(hide yes)
			(effects
				(font
					(size 1.27 1.27)
					(thickness 0.15)
				)
			)
		)
		(property "Author" "Antmicro"
			(at 0 0 0)
			(layer "B.Fab")
			(hide yes)
			(effects
				(font
					(size 1 1)
					(thickness 0.15)
				)
				(justify mirror)
			)
		)
		(property "Dielectric" ""
			(at 0 0 0)
			(layer "B.Fab")
			(hide yes)
			(effects
				(font
					(size 1 1)
					(thickness 0.15)
				)
				(justify mirror)
			)
		)
		(property "License" "Apache-2.0"
			(at 0 0 0)
			(layer "B.Fab")
			(hide yes)
			(effects
				(font
					(size 1 1)
					(thickness 0.15)
				)
				(justify mirror)
			)
		)
		(property "MPN" "06031C103JAT2A"
			(at 0 0 0)
			(layer "B.Fab")
			(hide yes)
			(effects
				(font
					(size 1 1)
					(thickness 0.15)
				)
				(justify mirror)
			)
		)
		(property "Manufacturer" "AVX"
			(at 0 0 0)
			(layer "B.Fab")
			(hide yes)
			(effects
				(font
					(size 1 1)
					(thickness 0.15)
				)
				(justify mirror)
			)
		)
		(property "Val" "10n"
			(at 0 0 0)
			(layer "B.Fab")
			(hide yes)
			(effects
				(font
					(size 1 1)
					(thickness 0.15)
				)
				(justify mirror)
			)
		)
		(property "Voltage" ""
			(at 0 0 0)
			(layer "B.Fab")
			(hide yes)
			(effects
				(font
					(size 1 1)
					(thickness 0.15)
				)
				(justify mirror)
			)
		)
		(sheetname "Supply")
		(sheetfile "supply.kicad_sch")
		(attr smd)
		(fp_line
			(start -0.3 -0.3)
			(end 0.3 -0.3)
			(stroke
				(width 0.15)
				(type solid)
			)
			(layer "B.SilkS")
		)
		(fp_line
			(start -0.3 0.3)
			(end 0.3 0.3)
			(stroke
				(width 0.15)
				(type solid)
			)
			(layer "B.SilkS")
		)
		(fp_rect
			(start -1.24 0.7)
			(end 1.24 -0.7)
			(stroke
				(width 0.05)
				(type solid)
			)
			(fill no)
			(layer "B.CrtYd")
		)
		(fp_rect
			(start -0.8 0.4)
			(end 0.8 -0.4)
			(stroke
				(width 0.15)
				(type solid)
			)
			(fill no)
			(layer "B.Fab")
		)
		(pad "1" smd roundrect
			(at -0.7 0)
			(size 0.6 0.8)
			(layers "B.Cu" "B.Mask" "B.Paste")
			(roundrect_rratio 0.2)
			(net 66 "VDDQ")
			(pintype "passive")
		)
		(pad "2" smd roundrect
			(at 0.7 0)
			(size 0.6 0.8)
			(layers "B.Cu" "B.Mask" "B.Paste")
			(roundrect_rratio 0.2)
			(net 5 "GND")
			(pintype "passive")
		)
	)
)
